(kicad_pcb
	(version 20260206)
	(generator "pcbnew")
	(generator_version "10.0")
	(general
		(thickness 1.6)
		(legacy_teardrops no)
	)
	(paper "A4")
	(title_block
		(title "peb — Lightning_PEB_BRD.brd")
		(comment 1 "Lightning (Wiwynn / Facebook NVMe JBOF) / footprints 233-239 of 2563")
	)
	(layers
		(0 "F.Cu" signal "TOP")
		(4 "In1.Cu" signal "L2GND")
		(6 "In2.Cu" signal "L3")
		(8 "In3.Cu" signal "L4VCC")
		(10 "In4.Cu" signal "L5VCC")
		(12 "In5.Cu" signal "L6")
		(14 "In6.Cu" signal "L7GND")
		(2 "B.Cu" signal "BOTTOM")
		(9 "F.Adhes" user "F.Adhesive")
		(11 "B.Adhes" user "B.Adhesive")
		(13 "F.Paste" user "Package Geometry/Pastemask Top")
		(15 "B.Paste" user "Package Geometry/Pastemask Bottom")
		(5 "F.SilkS" user "Ref Des/Silkscreen Top")
		(7 "B.SilkS" user "Ref Des/Silkscreen Bottom")
		(1 "F.Mask" user "Board Geometry/Soldermask Top")
		(3 "B.Mask" user "Board Geometry/Soldermask Bottom")
		(17 "Dwgs.User" user "User.Drawings")
		(19 "Cmts.User" user "User.Comments")
		(21 "Eco1.User" user "User.Eco1")
		(23 "Eco2.User" user "User.Eco2")
		(25 "Edge.Cuts" user "Board Geometry/Outline")
		(27 "Margin" user)
		(31 "F.CrtYd" user "Package Geometry/Place Bound Top")
		(29 "B.CrtYd" user "Package Geometry/Place Bound Bottom")
		(35 "F.Fab" user "Ref Des/Assembly Top")
		(33 "B.Fab" user "Ref Des/Assembly Bottom")
	)
	(footprint ""
		(layer "F.Cu")
		(at 345.821 -68.199 180)
		(property "Reference" "PR158"
			(at 0 0 180)
			(layer "F.SilkS")
			(hide yes)
			(effects
				(font
					(size 1.27 1.27)
				)
			)
		)
		(property "Value" "100KR2F-L1-GP"
			(at 0.064008 -3.993896 180)
			(unlocked yes)
			(layer "F.Fab")
			(hide yes)
			(effects
				(font
					(size 1.016 1.016)
					(thickness 0.1524)
				)
			)
		)
		(property "Device Type" "R402H16"
			(at 0.064008 -5.517896 180)
			(unlocked yes)
			(layer "F.Fab")
			(hide yes)
			(effects
				(font
					(size 1.016 1.016)
					(thickness 0.1524)
				)
			)
		)
		(duplicate_pad_numbers_are_jumpers no)
		(fp_line
			(start 0.508 -0.9398)
			(end -0.508 -0.9398)
			(stroke
				(width 0.1524)
				(type default)
			)
			(layer "F.SilkS")
		)
		(fp_line
			(start -0.508 -0.9398)
			(end -0.508 0.9398)
			(stroke
				(width 0.1524)
				(type default)
			)
			(layer "F.SilkS")
		)
		(fp_rect
			(start -0.508 0.9398)
			(end 0.508 -0.9398)
			(stroke
				(width 0)
				(type default)
			)
			(fill no)
			(layer "F.CrtYd")
		)
		(fp_rect
			(start -0.508 0.9398)
			(end 0.508 -0.9398)
			(stroke
				(width 0)
				(type default)
			)
			(fill no)
			(layer "F.Fab")
		)
		(pad "1" smd custom
			(at 0 -0.4445 180)
			(size 0.1397 0.1397)
			(layers "F.Cu" "F.Mask" "F.Paste")
			(net "P0V9_E_VREG")
			(options
				(clearance outline)
				(anchor circle)
			)
			(primitives
				(gr_poly
					(pts
						(arc
							(start -0.1778 -0.2794)
							(mid -0.249642 -0.249642)
							(end -0.2794 -0.1778)
						)
						(arc
							(start -0.2794 0.1778)
							(mid -0.249642 0.249642)
							(end -0.1778 0.2794)
						)
						(arc
							(start 0.1778 0.2794)
							(mid 0.249642 0.249642)
							(end 0.2794 0.1778)
						)
						(arc
							(start 0.2794 -0.1778)
							(mid 0.249642 -0.249642)
							(end 0.1778 -0.2794)
						)
					)
					(width 0)
					(fill yes)
				)
			)
		)
		(pad "2" smd custom
			(at 0 0.4445 180)
			(size 0.1397 0.1397)
			(layers "F.Cu" "F.Mask" "F.Paste")
			(net "P0V9_E_RF")
			(options
				(clearance outline)
				(anchor circle)
			)
			(primitives
				(gr_poly
					(pts
						(arc
							(start -0.1778 -0.2794)
							(mid -0.249642 -0.249642)
							(end -0.2794 -0.1778)
						)
						(arc
							(start -0.2794 0.1778)
							(mid -0.249642 0.249642)
							(end -0.1778 0.2794)
						)
						(arc
							(start 0.1778 0.2794)
							(mid 0.249642 0.249642)
							(end 0.2794 0.1778)
						)
						(arc
							(start 0.2794 -0.1778)
							(mid 0.249642 -0.249642)
							(end 0.1778 -0.2794)
						)
					)
					(width 0)
					(fill yes)
				)
			)
		)
	)
	(footprint ""
		(layer "F.Cu")
		(at 140.32992 -33.9217 90)
		(property "Reference" "R274"
			(at 0 0 90)
			(layer "F.SilkS")
			(hide yes)
			(effects
				(font
					(size 1.27 1.27)
				)
			)
		)
		(property "Value" "0R2J-2-GP"
			(at 0.064008 -3.993896 90)
			(unlocked yes)
			(layer "F.Fab")
			(hide yes)
			(effects
				(font
					(size 1.016 1.016)
					(thickness 0.1524)
				)
			)
		)
		(property "Device Type" "R402H16"
			(at 0.064008 -5.517896 90)
			(unlocked yes)
			(layer "F.Fab")
			(hide yes)
			(effects
				(font
					(size 1.016 1.016)
					(thickness 0.1524)
				)
			)
		)
		(duplicate_pad_numbers_are_jumpers no)
		(fp_line
			(start 0.508 -0.9398)
			(end -0.508 -0.9398)
			(stroke
				(width 0.1524)
				(type default)
			)
			(layer "F.SilkS")
		)
		(fp_line
			(start -0.508 -0.9398)
			(end -0.508 0.9398)
			(stroke
				(width 0.1524)
				(type default)
			)
			(layer "F.SilkS")
		)
		(fp_rect
			(start -0.508 0.9398)
			(end 0.508 -0.9398)
			(stroke
				(width 0)
				(type default)
			)
			(fill no)
			(layer "F.CrtYd")
		)
		(fp_rect
			(start -0.508 0.9398)
			(end 0.508 -0.9398)
			(stroke
				(width 0)
				(type default)
			)
			(fill no)
			(layer "F.Fab")
		)
		(pad "1" smd custom
			(at 0 -0.4445 90)
			(size 0.1397 0.1397)
			(layers "F.Cu" "F.Mask" "F.Paste")
			(net "MINISAS_CN15_B_I2C_INT#")
			(options
				(clearance outline)
				(anchor circle)
			)
			(primitives
				(gr_poly
					(pts
						(arc
							(start -0.1778 -0.2794)
							(mid -0.249642 -0.249642)
							(end -0.2794 -0.1778)
						)
						(arc
							(start -0.2794 0.1778)
							(mid -0.249642 0.249642)
							(end -0.1778 0.2794)
						)
						(arc
							(start 0.1778 0.2794)
							(mid 0.249642 0.249642)
							(end 0.2794 0.1778)
						)
						(arc
							(start 0.2794 -0.1778)
							(mid 0.249642 -0.249642)
							(end 0.1778 -0.2794)
						)
					)
					(width 0)
					(fill yes)
				)
			)
		)
		(pad "2" smd custom
			(at 0 0.4445 90)
			(size 0.1397 0.1397)
			(layers "F.Cu" "F.Mask" "F.Paste")
			(net "CLK_N_2")
			(options
				(clearance outline)
				(anchor circle)
			)
			(primitives
				(gr_poly
					(pts
						(arc
							(start -0.1778 -0.2794)
							(mid -0.249642 -0.249642)
							(end -0.2794 -0.1778)
						)
						(arc
							(start -0.2794 0.1778)
							(mid -0.249642 0.249642)
							(end -0.1778 0.2794)
						)
						(arc
							(start 0.1778 0.2794)
							(mid 0.249642 0.249642)
							(end 0.2794 0.1778)
						)
						(arc
							(start 0.2794 -0.1778)
							(mid 0.249642 -0.249642)
							(end 0.1778 -0.2794)
						)
					)
					(width 0)
					(fill yes)
				)
			)
		)
	)
	(footprint ""
		(layer "F.Cu")
		(at 321.691 -86.487 180)
		(property "Reference" "R526"
			(at 0 0 180)
			(layer "F.SilkS")
			(hide yes)
			(effects
				(font
					(size 1.27 1.27)
				)
			)
		)
		(property "Value" "10KR2F-2-GP"
			(at 0.064008 -3.993896 180)
			(unlocked yes)
			(layer "F.Fab")
			(hide yes)
			(effects
				(font
					(size 1.016 1.016)
					(thickness 0.1524)
				)
			)
		)
		(property "Device Type" "R402H16"
			(at 0.064008 -5.517896 180)
			(unlocked yes)
			(layer "F.Fab")
			(hide yes)
			(effects
				(font
					(size 1.016 1.016)
					(thickness 0.1524)
				)
			)
		)
		(duplicate_pad_numbers_are_jumpers no)
		(fp_line
			(start 0.508 -0.9398)
			(end -0.508 -0.9398)
			(stroke
				(width 0.1524)
				(type default)
			)
			(layer "F.SilkS")
		)
		(fp_line
			(start -0.508 -0.9398)
			(end -0.508 0.9398)
			(stroke
				(width 0.1524)
				(type default)
			)
			(layer "F.SilkS")
		)
		(fp_rect
			(start -0.508 0.9398)
			(end 0.508 -0.9398)
			(stroke
				(width 0)
				(type default)
			)
			(fill no)
			(layer "F.CrtYd")
		)
		(fp_rect
			(start -0.508 0.9398)
			(end 0.508 -0.9398)
			(stroke
				(width 0)
				(type default)
			)
			(fill no)
			(layer "F.Fab")
		)
		(pad "1" smd custom
			(at 0 -0.4445 180)
			(size 0.1397 0.1397)
			(layers "F.Cu" "F.Mask" "F.Paste")
			(net "GND")
			(options
				(clearance outline)
				(anchor circle)
			)
			(primitives
				(gr_poly
					(pts
						(arc
							(start -0.1778 -0.2794)
							(mid -0.249642 -0.249642)
							(end -0.2794 -0.1778)
						)
						(arc
							(start -0.2794 0.1778)
							(mid -0.249642 0.249642)
							(end -0.1778 0.2794)
						)
						(arc
							(start 0.1778 0.2794)
							(mid 0.249642 0.249642)
							(end 0.2794 0.1778)
						)
						(arc
							(start 0.2794 -0.1778)
							(mid 0.249642 -0.249642)
							(end 0.1778 -0.2794)
						)
					)
					(width 0)
					(fill yes)
				)
			)
		)
		(pad "2" smd custom
			(at 0 0.4445 180)
			(size 0.1397 0.1397)
			(layers "F.Cu" "F.Mask" "F.Paste")
			(net "IOEXP_PMC1_AD2")
			(options
				(clearance outline)
				(anchor circle)
			)
			(primitives
				(gr_poly
					(pts
						(arc
							(start -0.1778 -0.2794)
							(mid -0.249642 -0.249642)
							(end -0.2794 -0.1778)
						)
						(arc
							(start -0.2794 0.1778)
							(mid -0.249642 0.249642)
							(end -0.1778 0.2794)
						)
						(arc
							(start 0.1778 0.2794)
							(mid 0.249642 0.249642)
							(end 0.2794 0.1778)
						)
						(arc
							(start 0.2794 -0.1778)
							(mid 0.249642 -0.249642)
							(end 0.1778 -0.2794)
						)
					)
					(width 0)
					(fill yes)
				)
			)
		)
	)
	(footprint ""
		(layer "F.Cu")
		(at 76.108306 -84.937854)
		(property "Reference" "R485"
			(at 0 0 0)
			(layer "F.SilkS")
			(hide yes)
			(effects
				(font
					(size 1.27 1.27)
				)
			)
		)
		(property "Value" "1KR2F-3-GP"
			(at 0.064008 -3.993896 0)
			(unlocked yes)
			(layer "F.Fab")
			(hide yes)
			(effects
				(font
					(size 1.016 1.016)
					(thickness 0.1524)
				)
			)
		)
		(property "Device Type" "R402H16"
			(at 0.064008 -5.517896 0)
			(unlocked yes)
			(layer "F.Fab")
			(hide yes)
			(effects
				(font
					(size 1.016 1.016)
					(thickness 0.1524)
				)
			)
		)
		(duplicate_pad_numbers_are_jumpers no)
		(fp_line
			(start -0.508 -0.9398)
			(end -0.508 0.9398)
			(stroke
				(width 0.1524)
				(type default)
			)
			(layer "F.SilkS")
		)
		(fp_line
			(start 0.508 -0.9398)
			(end -0.508 -0.9398)
			(stroke
				(width 0.1524)
				(type default)
			)
			(layer "F.SilkS")
		)
		(fp_rect
			(start -0.508 0.9398)
			(end 0.508 -0.9398)
			(stroke
				(width 0)
				(type default)
			)
			(fill no)
			(layer "F.CrtYd")
		)
		(fp_rect
			(start -0.508 0.9398)
			(end 0.508 -0.9398)
			(stroke
				(width 0)
				(type default)
			)
			(fill no)
			(layer "F.Fab")
		)
		(pad "1" smd custom
			(at 0 -0.4445)
			(size 0.1397 0.1397)
			(layers "F.Cu" "F.Mask" "F.Paste")
			(net "DIVIDER_2_IN")
			(options
				(clearance outline)
				(anchor circle)
			)
			(primitives
				(gr_poly
					(pts
						(arc
							(start -0.1778 -0.2794)
							(mid -0.249642 -0.249642)
							(end -0.2794 -0.1778)
						)
						(arc
							(start -0.2794 0.1778)
							(mid -0.249642 0.249642)
							(end -0.1778 0.2794)
						)
						(arc
							(start 0.1778 0.2794)
							(mid 0.249642 0.249642)
							(end 0.2794 0.1778)
						)
						(arc
							(start 0.2794 -0.1778)
							(mid 0.249642 -0.249642)
							(end 0.1778 -0.2794)
						)
					)
					(width 0)
					(fill yes)
				)
			)
		)
		(pad "2" smd custom
			(at 0 0.4445)
			(size 0.1397 0.1397)
			(layers "F.Cu" "F.Mask" "F.Paste")
			(net "GND")
			(options
				(clearance outline)
				(anchor circle)
			)
			(primitives
				(gr_poly
					(pts
						(arc
							(start -0.1778 -0.2794)
							(mid -0.249642 -0.249642)
							(end -0.2794 -0.1778)
						)
						(arc
							(start -0.2794 0.1778)
							(mid -0.249642 0.249642)
							(end -0.1778 0.2794)
						)
						(arc
							(start 0.1778 0.2794)
							(mid 0.249642 0.249642)
							(end 0.2794 0.1778)
						)
						(arc
							(start 0.2794 -0.1778)
							(mid 0.249642 -0.249642)
							(end 0.1778 -0.2794)
						)
					)
					(width 0)
					(fill yes)
				)
			)
		)
	)
	(footprint ""
		(layer "F.Cu")
		(at 319.592198 -212.420454 180)
		(property "Reference" "C67"
			(at 0 0 180)
			(layer "F.SilkS")
			(hide yes)
			(effects
				(font
					(size 1.27 1.27)
				)
			)
		)
		(property "Value" "SCD22U10V2KX-1GP"
			(at 1.1811 -2.7051 180)
			(unlocked yes)
			(layer "F.Fab")
			(hide yes)
			(effects
				(font
					(size 1.016 1.016)
					(thickness 0.1524)
				)
			)
		)
		(property "Device Type" "C402H22"
			(at 1.1811 -4.2291 180)
			(unlocked yes)
			(layer "F.Fab")
			(hide yes)
			(effects
				(font
					(size 1.016 1.016)
					(thickness 0.1524)
				)
			)
		)
		(duplicate_pad_numbers_are_jumpers no)
		(fp_rect
			(start -0.4318 0.9525)
			(end 0.4318 -0.9525)
			(stroke
				(width 0)
				(type default)
			)
			(fill no)
			(layer "F.CrtYd")
		)
		(fp_rect
			(start -0.4318 0.9525)
			(end 0.4318 -0.9525)
			(stroke
				(width 0)
				(type default)
			)
			(fill no)
			(layer "F.Fab")
		)
		(pad "1" smd custom
			(at 0 -0.4445 180)
			(size 0.1524 0.1524)
			(layers "F.Cu" "F.Mask" "F.Paste")
			(net "PCIE_TX_CAP_P22")
			(options
				(clearance outline)
				(anchor circle)
			)
			(primitives
				(gr_poly
					(pts
						(arc
							(start 0.3048 -0.2032)
							(mid 0.275042 -0.275042)
							(end 0.2032 -0.3048)
						)
						(arc
							(start -0.2032 -0.3048)
							(mid -0.275042 -0.275042)
							(end -0.3048 -0.2032)
						)
						(arc
							(start -0.3048 0.2032)
							(mid -0.275042 0.275042)
							(end -0.2032 0.3048)
						)
						(arc
							(start 0.2032 0.3048)
							(mid 0.275042 0.275042)
							(end 0.3048 0.2032)
						)
					)
					(width 0)
					(fill yes)
				)
			)
		)
		(pad "2" smd custom
			(at 0 0.4445 180)
			(size 0.1524 0.1524)
			(layers "F.Cu" "F.Mask" "F.Paste")
			(net "PCIE_TX_P22")
			(options
				(clearance outline)
				(anchor circle)
			)
			(primitives
				(gr_poly
					(pts
						(arc
							(start 0.3048 -0.2032)
							(mid 0.275042 -0.275042)
							(end 0.2032 -0.3048)
						)
						(arc
							(start -0.2032 -0.3048)
							(mid -0.275042 -0.275042)
							(end -0.3048 -0.2032)
						)
						(arc
							(start -0.3048 0.2032)
							(mid -0.275042 0.275042)
							(end -0.2032 0.3048)
						)
						(arc
							(start 0.2032 0.3048)
							(mid 0.275042 0.275042)
							(end 0.3048 0.2032)
						)
					)
					(width 0)
					(fill yes)
				)
			)
		)
	)
	(footprint ""
		(layer "F.Cu")
		(at 16.256 -145.415 90)
		(property "Reference" "L5"
			(at 0 0 90)
			(layer "F.SilkS")
			(hide yes)
			(effects
				(font
					(size 1.27 1.27)
				)
			)
		)
		(property "Value" "MMZ2012S601ATA1N-GP"
			(at 0 -4.2418 90)
			(unlocked yes)
			(layer "F.Fab")
			(hide yes)
			(effects
				(font
					(size 1.016 1.016)
					(thickness 0.1524)
				)
			)
		)
		(property "Device Type" "L805H42"
			(at 0 -5.7912 90)
			(unlocked yes)
			(layer "F.Fab")
			(hide yes)
			(effects
				(font
					(size 1.016 1.016)
					(thickness 0.1524)
				)
			)
		)
		(duplicate_pad_numbers_are_jumpers no)
		(fp_line
			(start 0.889 -1.7018)
			(end 0.889 1.7018)
			(stroke
				(width 0.1524)
				(type default)
			)
			(layer "F.SilkS")
		)
		(fp_line
			(start -0.889 -1.7018)
			(end 0.889 -1.7018)
			(stroke
				(width 0.1524)
				(type default)
			)
			(layer "F.SilkS")
		)
		(fp_line
			(start 0.889 1.7018)
			(end -0.889 1.7018)
			(stroke
				(width 0.1524)
				(type default)
			)
			(layer "F.SilkS")
		)
		(fp_line
			(start -0.889 1.7018)
			(end -0.889 -1.7018)
			(stroke
				(width 0.1524)
				(type default)
			)
			(layer "F.SilkS")
		)
		(fp_rect
			(start -0.9652 1.778)
			(end 0.9652 -1.778)
			(stroke
				(width 0)
				(type default)
			)
			(fill no)
			(layer "F.CrtYd")
		)
		(fp_rect
			(start -0.9652 1.778)
			(end 0.9652 -1.778)
			(stroke
				(width 0)
				(type default)
			)
			(fill no)
			(layer "F.Fab")
		)
		(pad "1" smd rect
			(at 0 -0.9652 90)
			(size 1.397 1.143)
			(layers "F.Cu" "F.Mask" "F.Paste")
			(net "P3V3_STBY")
		)
		(pad "2" smd rect
			(at 0 0.9652 90)
			(size 1.397 1.143)
			(layers "F.Cu" "F.Mask" "F.Paste")
			(net "MPLLAV33")
		)
	)
	(footprint ""
		(layer "F.Cu")
		(at 333.381604 -38.404546 90)
		(property "Reference" "R624"
			(at 0 0 90)
			(layer "F.SilkS")
			(hide yes)
			(effects
				(font
					(size 1.27 1.27)
				)
			)
		)
		(property "Value" "0R2J-2-GP"
			(at 0.064008 -3.993896 90)
			(unlocked yes)
			(layer "F.Fab")
			(hide yes)
			(effects
				(font
					(size 1.016 1.016)
					(thickness 0.1524)
				)
			)
		)
		(property "Device Type" "R402H16"
			(at 0.064008 -5.517896 90)
			(unlocked yes)
			(layer "F.Fab")
			(hide yes)
			(effects
				(font
					(size 1.016 1.016)
					(thickness 0.1524)
				)
			)
		)
		(duplicate_pad_numbers_are_jumpers no)
		(fp_line
			(start 0.508 -0.9398)
			(end -0.508 -0.9398)
			(stroke
				(width 0.1524)
				(type default)
			)
			(layer "F.SilkS")
		)
		(fp_line
			(start -0.508 -0.9398)
			(end -0.508 0.9398)
			(stroke
				(width 0.1524)
				(type default)
			)
			(layer "F.SilkS")
		)
		(fp_rect
			(start -0.508 0.9398)
			(end 0.508 -0.9398)
			(stroke
				(width 0)
				(type default)
			)
			(fill no)
			(layer "F.CrtYd")
		)
		(fp_rect
			(start -0.508 0.9398)
			(end 0.508 -0.9398)
			(stroke
				(width 0)
				(type default)
			)
			(fill no)
			(layer "F.Fab")
		)
		(pad "1" smd custom
			(at 0 -0.4445 90)
			(size 0.1397 0.1397)
			(layers "F.Cu" "F.Mask" "F.Paste")
			(net "UPLINK5_R")
			(options
				(clearance outline)
				(anchor circle)
			)
			(primitives
				(gr_poly
					(pts
						(arc
							(start -0.1778 -0.2794)
							(mid -0.249642 -0.249642)
							(end -0.2794 -0.1778)
						)
						(arc
							(start -0.2794 0.1778)
							(mid -0.249642 0.249642)
							(end -0.1778 0.2794)
						)
						(arc
							(start 0.1778 0.2794)
							(mid 0.249642 0.249642)
							(end 0.2794 0.1778)
						)
						(arc
							(start 0.2794 -0.1778)
							(mid 0.249642 -0.249642)
							(end 0.1778 -0.2794)
						)
					)
					(width 0)
					(fill yes)
				)
			)
		)
		(pad "2" smd custom
			(at 0 0.4445 90)
			(size 0.1397 0.1397)
			(layers "F.Cu" "F.Mask" "F.Paste")
			(net "UPLINK5")
			(options
				(clearance outline)
				(anchor circle)
			)
			(primitives
				(gr_poly
					(pts
						(arc
							(start -0.1778 -0.2794)
							(mid -0.249642 -0.249642)
							(end -0.2794 -0.1778)
						)
						(arc
							(start -0.2794 0.1778)
							(mid -0.249642 0.249642)
							(end -0.1778 0.2794)
						)
						(arc
							(start 0.1778 0.2794)
							(mid 0.249642 0.249642)
							(end 0.2794 0.1778)
						)
						(arc
							(start 0.2794 -0.1778)
							(mid 0.249642 -0.249642)
							(end 0.1778 -0.2794)
						)
					)
					(width 0)
					(fill yes)
				)
			)
		)
	)
)
